# T6G (Grand Teton) — schematic netlist excerpt (pin names and nets, part order shuffled) for the footprints in the layout excerpt that follows; sources: Cadence DE-HDL packaged netlist, KiCad conversion of 04192023_DAF0TMB3IC0_F0TG_MB_C_brd_V02_OCP.brd

PR3981  Q_RES  0 5% CHIP  pkg 0402LF  page 264 : A = HSC_VDD_R_4 ; B = HSC_VDD
PR337  Q_RES  1K 1% CHIP  pkg 0402LF  page 211 : A = PVDDCR_CPU0_P1 ; B = GND

(kicad_pcb
	(version 20260206)
	(generator "pcbnew")
	(generator_version "10.0")
	(general
		(thickness 1.6)
		(legacy_teardrops no)
	)
	(paper "A4")
	(title_block
		(title "04192023_DAF0TMB3IC0_F0TG_MB_C_brd_V02_OCP.brd")
		(comment 1 "Grand Teton / footprints 8160-8161 of 8354")
	)
	(layers
		(0 "F.Cu" signal "TOP")
		(4 "In1.Cu" signal "GND")
		(6 "In2.Cu" signal "IN1")
		(8 "In3.Cu" signal "GND1")
		(10 "In4.Cu" signal "IN2")
		(12 "In5.Cu" signal "GND2")
		(14 "In6.Cu" signal "IN3")
		(16 "In7.Cu" signal "GND3")
		(18 "In8.Cu" signal "VCC")
		(20 "In9.Cu" signal "VCC1")
		(22 "In10.Cu" signal "GND4")
		(24 "In11.Cu" signal "IN4")
		(26 "In12.Cu" signal "GND5")
		(28 "In13.Cu" signal "IN5")
		(30 "In14.Cu" signal "GND6")
		(32 "In15.Cu" signal "IN6")
		(34 "In16.Cu" signal "GND7")
		(2 "B.Cu" signal "BOTTOM")
		(9 "F.Adhes" user "F.Adhesive")
		(11 "B.Adhes" user "B.Adhesive")
		(13 "F.Paste" user "Package Geometry/Pastemask Top")
		(15 "B.Paste" user "Package Geometry/Pastemask Bottom")
		(5 "F.SilkS" user "Ref Des/Silkscreen Top")
		(7 "B.SilkS" user "Ref Des/Silkscreen Bottom")
		(1 "F.Mask" user "Board Geometry/Soldermask Top")
		(3 "B.Mask" user "Board Geometry/Soldermask Bottom")
		(17 "Dwgs.User" user "User.Drawings")
		(19 "Cmts.User" user "User.Comments")
		(21 "Eco1.User" user "User.Eco1")
		(23 "Eco2.User" user "User.Eco2")
		(25 "Edge.Cuts" user "Board Geometry/Outline")
		(27 "Margin" user)
		(31 "F.CrtYd" user "Package Geometry/Place Bound Top")
		(29 "B.CrtYd" user "Package Geometry/Place Bound Bottom")
		(35 "F.Fab" user "Ref Des/Assembly Top")
		(33 "B.Fab" user "Ref Des/Assembly Bottom")
	)
	(footprint ""
		(layer "B.Cu")
		(at 225.9203 -402.744432 -90)
		(property "Reference" "PR3981"
			(at 0 0 90)
			(layer "B.SilkS")
			(hide yes)
			(effects
				(font
					(size 1.27 1.27)
				)
				(justify mirror)
			)
		)
		(property "Value" ""
			(at 0 0 90)
			(layer "B.Fab")
			(effects
				(font
					(size 1.27 1.27)
				)
				(justify mirror)
			)
		)
		(duplicate_pad_numbers_are_jumpers no)
		(fp_line
			(start -0.7874 0.4064)
			(end 0.7874 0.4064)
			(stroke
				(width 0.1524)
				(type default)
			)
			(layer "B.SilkS")
		)
		(fp_line
			(start 0.7874 0.4064)
			(end 0.7874 -0.4064)
			(stroke
				(width 0.1524)
				(type default)
			)
			(layer "B.SilkS")
		)
		(fp_line
			(start -0.7874 -0.4064)
			(end -0.7874 0.4064)
			(stroke
				(width 0.1524)
				(type default)
			)
			(layer "B.SilkS")
		)
		(fp_line
			(start 0.7874 -0.4064)
			(end -0.7874 -0.4064)
			(stroke
				(width 0.1524)
				(type default)
			)
			(layer "B.SilkS")
		)
		(fp_line
			(start -0.67945 0.3048)
			(end -0.120396 0.3048)
			(stroke
				(width 0.1)
				(type default)
			)
			(layer "B.Fab")
		)
		(fp_line
			(start -0.120396 0.3048)
			(end -0.120396 0.2794)
			(stroke
				(width 0.1)
				(type default)
			)
			(layer "B.Fab")
		)
		(fp_line
			(start 0.12065 0.3048)
			(end 0.67945 0.3048)
			(stroke
				(width 0.1)
				(type default)
			)
			(layer "B.Fab")
		)
		(fp_line
			(start 0.67945 0.3048)
			(end 0.67945 -0.305054)
			(stroke
				(width 0.1)
				(type default)
			)
			(layer "B.Fab")
		)
		(fp_line
			(start -0.120396 0.2794)
			(end 0.12065 0.2794)
			(stroke
				(width 0.1)
				(type default)
			)
			(layer "B.Fab")
		)
		(fp_line
			(start 0.12065 0.2794)
			(end 0.12065 0.3048)
			(stroke
				(width 0.1)
				(type default)
			)
			(layer "B.Fab")
		)
		(fp_line
			(start -0.12065 -0.2794)
			(end -0.12065 -0.3048)
			(stroke
				(width 0.1)
				(type default)
			)
			(layer "B.Fab")
		)
		(fp_line
			(start 0.12065 -0.2794)
			(end -0.12065 -0.2794)
			(stroke
				(width 0.1)
				(type default)
			)
			(layer "B.Fab")
		)
		(fp_line
			(start -0.67945 -0.3048)
			(end -0.67945 0.3048)
			(stroke
				(width 0.1)
				(type default)
			)
			(layer "B.Fab")
		)
		(fp_line
			(start -0.12065 -0.3048)
			(end -0.67945 -0.3048)
			(stroke
				(width 0.1)
				(type default)
			)
			(layer "B.Fab")
		)
		(fp_line
			(start 0.12065 -0.305054)
			(end 0.12065 -0.2794)
			(stroke
				(width 0.1)
				(type default)
			)
			(layer "B.Fab")
		)
		(fp_line
			(start 0.67945 -0.305054)
			(end 0.12065 -0.305054)
			(stroke
				(width 0.1)
				(type default)
			)
			(layer "B.Fab")
		)
		(pad "1" smd circle
			(at 0.40005 0 90)
			(size 0 0)
			(layers "B.Cu" "B.Mask" "B.Paste")
			(net "HSC_VDD_R_4")
		)
		(pad "2" smd circle
			(at -0.40005 0 90)
			(size 0 0)
			(layers "B.Cu" "B.Mask" "B.Paste")
			(net "HSC_VDD")
		)
	)
	(footprint ""
		(layer "B.Cu")
		(at 59.646058 -177.310542 90)
		(property "Reference" "PR337"
			(at 0 0 90)
			(layer "B.SilkS")
			(hide yes)
			(effects
				(font
					(size 1.27 1.27)
				)
				(justify mirror)
			)
		)
		(property "Value" ""
			(at 0 0 90)
			(layer "B.Fab")
			(effects
				(font
					(size 1.27 1.27)
				)
				(justify mirror)
			)
		)
		(duplicate_pad_numbers_are_jumpers no)
		(fp_line
			(start 0.7874 -0.4064)
			(end -0.7874 -0.4064)
			(stroke
				(width 0.1524)
				(type default)
			)
			(layer "B.SilkS")
		)
		(fp_line
			(start -0.7874 -0.4064)
			(end -0.7874 0.4064)
			(stroke
				(width 0.1524)
				(type default)
			)
			(layer "B.SilkS")
		)
		(fp_line
			(start 0.7874 0.4064)
			(end 0.7874 -0.4064)
			(stroke
				(width 0.1524)
				(type default)
			)
			(layer "B.SilkS")
		)
		(fp_line
			(start -0.7874 0.4064)
			(end 0.7874 0.4064)
			(stroke
				(width 0.1524)
				(type default)
			)
			(layer "B.SilkS")
		)
		(fp_line
			(start 0.67945 -0.305054)
			(end 0.12065 -0.305054)
			(stroke
				(width 0.1)
				(type default)
			)
			(layer "B.Fab")
		)
		(fp_line
			(start 0.12065 -0.305054)
			(end 0.12065 -0.2794)
			(stroke
				(width 0.1)
				(type default)
			)
			(layer "B.Fab")
		)
		(fp_line
			(start -0.12065 -0.3048)
			(end -0.67945 -0.3048)
			(stroke
				(width 0.1)
				(type default)
			)
			(layer "B.Fab")
		)
		(fp_line
			(start -0.67945 -0.3048)
			(end -0.67945 0.3048)
			(stroke
				(width 0.1)
				(type default)
			)
			(layer "B.Fab")
		)
		(fp_line
			(start 0.12065 -0.2794)
			(end -0.12065 -0.2794)
			(stroke
				(width 0.1)
				(type default)
			)
			(layer "B.Fab")
		)
		(fp_line
			(start -0.12065 -0.2794)
			(end -0.12065 -0.3048)
			(stroke
				(width 0.1)
				(type default)
			)
			(layer "B.Fab")
		)
		(fp_line
			(start 0.12065 0.2794)
			(end 0.12065 0.3048)
			(stroke
				(width 0.1)
				(type default)
			)
			(layer "B.Fab")
		)
		(fp_line
			(start -0.120396 0.2794)
			(end 0.12065 0.2794)
			(stroke
				(width 0.1)
				(type default)
			)
			(layer "B.Fab")
		)
		(fp_line
			(start 0.67945 0.3048)
			(end 0.67945 -0.305054)
			(stroke
				(width 0.1)
				(type default)
			)
			(layer "B.Fab")
		)
		(fp_line
			(start 0.12065 0.3048)
			(end 0.67945 0.3048)
			(stroke
				(width 0.1)
				(type default)
			)
			(layer "B.Fab")
		)
		(fp_line
			(start -0.120396 0.3048)
			(end -0.120396 0.2794)
			(stroke
				(width 0.1)
				(type default)
			)
			(layer "B.Fab")
		)
		(fp_line
			(start -0.67945 0.3048)
			(end -0.120396 0.3048)
			(stroke
				(width 0.1)
				(type default)
			)
			(layer "B.Fab")
		)
		(pad "1" smd circle
			(at 0.40005 0 270)
			(size 0 0)
			(layers "B.Cu" "B.Mask" "B.Paste")
			(net "PVDDCR_CPU0_P1")
		)
		(pad "2" smd circle
			(at -0.40005 0 270)
			(size 0 0)
			(layers "B.Cu" "B.Mask" "B.Paste")
			(net "GND")
		)
	)
)
